FILE_TYPE = MACRO_DRAWING;
SET COLOR_WIRE YELLOW;
SET COLOR_PROP MONO;
SET COLOR_DOT WHITE;
SET COLOR_ARC YELLOW;
SET COLOR_BODY GREEN;
SET COLOR_NOTE MONO;
SET PROP_DISPLAY VALUE;
SET PAGE_NUMBER P165;
FORCEADD ADC128D818..1
(-4325 2625);
FORCEPROP 1 LAST PART_NUMBER H63642-001
J 0
(-4625 2025);
DISPLAY 0.617021 (-4625 2025);
PAINT BLUE (-4625 2025);
FORCEPROP 2 LASTPIN (-4675 2175) $PN 16
J 2
(-4685 2185);
DISPLAY 0.617021 (-4685 2185);
PAINT ORANGE (-4685 2185);
FORCEPROP 2 LASTPIN (-4675 2225) $PN 15
J 2
(-4685 2235);
DISPLAY 0.617021 (-4685 2235);
PAINT ORANGE (-4685 2235);
FORCEPROP 2 LASTPIN (-4675 2275) $PN 14
J 2
(-4685 2285);
DISPLAY 0.617021 (-4685 2285);
PAINT ORANGE (-4685 2285);
FORCEPROP 2 LASTPIN (-4675 2475) $PN 10
J 2
(-4685 2485);
DISPLAY 0.617021 (-4685 2485);
PAINT ORANGE (-4685 2485);
FORCEPROP 2 LASTPIN (-4675 2425) $PN 11
J 2
(-4685 2435);
DISPLAY 0.617021 (-4685 2435);
PAINT ORANGE (-4685 2435);
FORCEPROP 2 LASTPIN (-4675 2375) $PN 12
J 2
(-4685 2385);
DISPLAY 0.617021 (-4685 2385);
PAINT ORANGE (-4685 2385);
FORCEPROP 2 LASTPIN (-4675 2325) $PN 13
J 2
(-4685 2335);
DISPLAY 0.617021 (-4685 2335);
PAINT ORANGE (-4685 2335);
FORCEPROP 2 LASTPIN (-4675 2525) $PN 9
J 2
(-4685 2535);
DISPLAY 0.617021 (-4685 2535);
PAINT ORANGE (-4685 2535);
FORCEPROP 2 LASTPIN (-4675 2625) $PN 7
J 2
(-4685 2635);
DISPLAY 0.617021 (-4685 2635);
PAINT ORANGE (-4685 2635);
FORCEPROP 2 LASTPIN (-4675 2675) $PN 8
J 2
(-4685 2685);
DISPLAY 0.617021 (-4685 2685);
PAINT ORANGE (-4685 2685);
FORCEPROP 2 LASTPIN (-4675 2775) $PN 1
J 2
(-4685 2785);
DISPLAY 0.617021 (-4685 2785);
PAINT ORANGE (-4685 2785);
FORCEPROP 2 LASTPIN (-4675 2925) $PN 3
J 2
(-4685 2935);
DISPLAY 0.617021 (-4685 2935);
PAINT ORANGE (-4685 2935);
FORCEPROP 2 LASTPIN (-4675 2875) $PN 2
J 2
(-4685 2885);
DISPLAY 0.617021 (-4685 2885);
PAINT ORANGE (-4685 2885);
FORCEPROP 2 LASTPIN (-4675 3025) $PN 5
J 2
(-4685 3035);
DISPLAY 0.617021 (-4685 3035);
PAINT ORANGE (-4685 3035);
FORCEPROP 1 LAST MATERIAL IC
J 0
(-4625 3225);
DISPLAY 0.617021 (-4625 3225);
PAINT SKYBLUE (-4625 3225);
FORCEPROP 1 LAST LOCATION EU9G1
J 0
(-4625 3275);
DISPLAY 0.617021 (-4625 3275);
PAINT AQUA (-4625 3275);
FORCEPROP 2 LASTPIN (-3975 2175) $PN 4
J 0
(-3965 2185);
DISPLAY 0.617021 (-3965 2185);
PAINT ORANGE (-3965 2185);
FORCEPROP 2 LASTPIN (-3975 3025) $PN 6
J 0
(-3965 3035);
DISPLAY 0.617021 (-3965 3035);
PAINT ORANGE (-3965 3035);
FORCEPROP 2 LAST CDS_LIB mstr_digital
J 0
(-4325 2625);
PAINT ORANGE (-4325 2625);
DISPLAY INVISIBLE (-4325 2625);
FORCEPROP 2 LAST ROOM HEC_VOLT_MONITOR
J 0
(-4625 3325);
DISPLAY 1.021277 (-4625 3325);
PAINT ORANGE (-4625 3325);
DISPLAY INVISIBLE (-4625 3325);
FORCEPROP 2 LAST CDS_LOCATION EU9G1
J 0
(-4625 3275);
DISPLAY 0.617021 (-4625 3275);
PAINT AQUA (-4625 3275);
DISPLAY INVISIBLE (-4625 3275);
FORCEPROP 2 LAST SEC 1
J 0
(-4625 3325);
DISPLAY 0.680851 (-4625 3325);
PAINT MONO (-4625 3325);
DISPLAY INVISIBLE (-4625 3325);
FORCEPROP 2 LAST SEC_TYPE SM
J 0
(-4625 3325);
DISPLAY 1.021277 (-4625 3325);
PAINT ORANGE (-4625 3325);
DISPLAY INVISIBLE (-4625 3325);
FORCEPROP 2 LAST BOM_COST SM_HM
J 0
(-4625 3375);
DISPLAY 1.021277 (-4625 3375);
PAINT ORANGE (-4625 3375);
DISPLAY INVISIBLE (-4625 3375);
FORCEPROP 1 LAST PACK_TYPE SM
J 0
(-4625 3325);
PAINT SKYBLUE (-4625 3325);
DISPLAY INVISIBLE (-4625 3325);
FORCEPROP 1 LAST PATH I52
J 0
(-4275 3225);
PAINT GREEN (-4275 3225);
DISPLAY INVISIBLE (-4275 3225);
FORCEADD OFFPAGE..1
(-5650 2925);
FORCEPROP 2 LAST $XR0 138 
J 0
(-5902 2925);
DISPLAY 0.638298 (-5902 2925);
PAINT MONO (-5902 2925);
FORCEPROP 2 LAST $XR1 167 
J 0
(-6022 2925);
DISPLAY 0.638298 (-6022 2925);
PAINT MONO (-6022 2925);
FORCEPROP 2 LAST CDS_LIB mstr_standard
J 0
(-5650 2925);
PAINT ORANGE (-5650 2925);
DISPLAY INVISIBLE (-5650 2925);
FORCEPROP 2 LAST PATH I53
J 0
(-5600 3000);
DISPLAY 1.021277 (-5600 3000);
PAINT ORANGE (-5600 3000);
DISPLAY INVISIBLE (-5600 3000);
FORCEPROP 1 LAST COMMENT_BODY TRUE
J 0
(-5525 2825);
DISPLAY 0.872340 (-5525 2825);
PAINT GREEN (-5525 2825);
DISPLAY INVISIBLE (-5525 2825);
FORCEPROP 1 LAST OFFPAGE TRUE
J 0
(-5325 2800);
DISPLAY 0.872340 (-5325 2800);
PAINT GREEN (-5325 2800);
DISPLAY INVISIBLE (-5325 2800);
FORCEADD OFFPAGE..6
(-5650 2875);
FORCEPROP 2 LAST $XR0 138 
J 0
(-5960 2875);
DISPLAY 0.638298 (-5960 2875);
PAINT MONO (-5960 2875);
FORCEPROP 2 LAST $XR1 167 
J 0
(-6080 2875);
DISPLAY 0.638298 (-6080 2875);
PAINT MONO (-6080 2875);
FORCEPROP 2 LAST CDS_LIB mstr_standard
J 0
(-5650 2875);
PAINT ORANGE (-5650 2875);
DISPLAY INVISIBLE (-5650 2875);
FORCEPROP 2 LAST PATH I54
J 0
(-5600 2950);
DISPLAY 1.021277 (-5600 2950);
PAINT ORANGE (-5600 2950);
DISPLAY INVISIBLE (-5600 2950);
FORCEPROP 1 LAST COMMENT_BODY TRUE
J 0
(-5550 2800);
DISPLAY 0.872340 (-5550 2800);
PAINT GREEN (-5550 2800);
DISPLAY INVISIBLE (-5550 2800);
FORCEPROP 1 LAST OFFPAGE TRUE
J 0
(-5325 2750);
DISPLAY 0.872340 (-5325 2750);
PAINT GREEN (-5325 2750);
DISPLAY INVISIBLE (-5325 2750);
FORCEADD RES..2
R 2
(-6275 2350);
FORCEPROP 1 LAST WATTAGE 1/16W
J 2
(-6315 2325);
DISPLAY 0.617021 (-6315 2325);
PAINT SKYBLUE (-6315 2325);
FORCEPROP 1 LAST MATERIAL CHIP
J 2
(-6315 2275);
DISPLAY 0.617021 (-6315 2275);
PAINT SKYBLUE (-6315 2275);
FORCEPROP 1 LAST PACK_TYPE 0402
J 2
(-6315 2175);
DISPLAY 0.617021 (-6315 2175);
PAINT SKYBLUE (-6315 2175);
FORCEPROP 1 LAST VALUE 4.75K
J 2
(-6320 2425);
DISPLAY 0.617021 (-6320 2425);
PAINT SKYBLUE (-6320 2425);
FORCEPROP 1 LAST PART_NUMBER G21796-072
J 2
(-6315 2225);
DISPLAY 0.617021 (-6315 2225);
PAINT BLUE (-6315 2225);
FORCEPROP 1 LAST LOCATION R1U45
J 2
(-6320 2475);
DISPLAY 0.617021 (-6320 2475);
PAINT AQUA (-6320 2475);
FORCEPROP 1 LAST TOLERANCE 1%
J 2
(-6320 2375);
DISPLAY 0.617021 (-6320 2375);
PAINT SKYBLUE (-6320 2375);
FORCEPROP 1 LASTPIN (-6275 2250) $PN 2
J 2
(-6280 2260);
DISPLAY 0.787234 (-6280 2260);
PAINT ORANGE (-6280 2260);
DISPLAY INVISIBLE (-6280 2260);
FORCEPROP 1 LASTPIN (-6275 2450) $PN 1
J 2
(-6280 2412);
DISPLAY 0.787234 (-6280 2412);
PAINT ORANGE (-6280 2412);
DISPLAY INVISIBLE (-6280 2412);
FORCEPROP 2 LAST CDS_LOCATION R1U45
J 2
(-6320 2475);
DISPLAY 0.617021 (-6320 2475);
PAINT AQUA (-6320 2475);
DISPLAY INVISIBLE (-6320 2475);
FORCEPROP 2 LAST CDS_LIB mstr_discrete
J 2
(-6275 2350);
PAINT ORANGE (-6275 2350);
DISPLAY INVISIBLE (-6275 2350);
FORCEPROP 2 LAST ROOM HEC_VOLT_MONITOR
J 2
(-6325 2525);
DISPLAY 1.021277 (-6325 2525);
PAINT ORANGE (-6325 2525);
DISPLAY INVISIBLE (-6325 2525);
FORCEPROP 1 LAST PATH I55
J 2
(-6325 2525);
DISPLAY 0.978723 (-6325 2525);
PAINT WHITE (-6325 2525);
DISPLAY INVISIBLE (-6325 2525);
FORCEPROP 2 LAST BOM_COST SM_HM
J 2
(-6325 2575);
DISPLAY 1.021277 (-6325 2575);
PAINT ORANGE (-6325 2575);
DISPLAY INVISIBLE (-6325 2575);
FORCEPROP 2 LAST CDS_SEC 1
J 2
(-6325 2575);
DISPLAY 1.021277 (-6325 2575);
PAINT ORANGE (-6325 2575);
DISPLAY INVISIBLE (-6325 2575);
FORCEPROP 2 LAST $SEC 1
J 2
(-6325 2575);
DISPLAY 0.680851 (-6325 2575);
PAINT MONO (-6325 2575);
DISPLAY INVISIBLE (-6325 2575);
FORCEADD RES..2
R 2
(-6650 2350);
FORCEPROP 1 LAST WATTAGE 1/16W
J 2
(-6690 2325);
DISPLAY 0.617021 (-6690 2325);
PAINT SKYBLUE (-6690 2325);
FORCEPROP 1 LAST MATERIAL CHIP
J 2
(-6690 2275);
DISPLAY 0.617021 (-6690 2275);
PAINT SKYBLUE (-6690 2275);
FORCEPROP 1 LAST PACK_TYPE 0402
J 2
(-6690 2175);
DISPLAY 0.617021 (-6690 2175);
PAINT SKYBLUE (-6690 2175);
FORCEPROP 1 LAST TOLERANCE 1%
J 2
(-6695 2375);
DISPLAY 0.617021 (-6695 2375);
PAINT SKYBLUE (-6695 2375);
FORCEPROP 1 LAST VALUE 4.75K
J 2
(-6695 2425);
DISPLAY 0.617021 (-6695 2425);
PAINT SKYBLUE (-6695 2425);
FORCEPROP 1 LAST PART_NUMBER G21796-072
J 2
(-6690 2225);
DISPLAY 0.617021 (-6690 2225);
PAINT BLUE (-6690 2225);
FORCEPROP 1 LAST LOCATION R1U48
J 2
(-6695 2475);
DISPLAY 0.617021 (-6695 2475);
PAINT AQUA (-6695 2475);
FORCEPROP 2 LAST CDS_LOCATION R1U48
J 2
(-6695 2475);
DISPLAY 0.617021 (-6695 2475);
PAINT AQUA (-6695 2475);
DISPLAY INVISIBLE (-6695 2475);
FORCEPROP 2 LAST ROOM HEC_VOLT_MONITOR
J 2
(-6700 2525);
DISPLAY 1.021277 (-6700 2525);
PAINT ORANGE (-6700 2525);
DISPLAY INVISIBLE (-6700 2525);
FORCEPROP 1 LAST PATH I56
J 2
(-6700 2525);
DISPLAY 0.978723 (-6700 2525);
PAINT WHITE (-6700 2525);
DISPLAY INVISIBLE (-6700 2525);
FORCEPROP 2 LAST $SEC 1
J 2
(-6700 2575);
DISPLAY 0.680851 (-6700 2575);
PAINT MONO (-6700 2575);
DISPLAY INVISIBLE (-6700 2575);
FORCEPROP 2 LAST CDS_SEC 1
J 2
(-6700 2575);
DISPLAY 1.021277 (-6700 2575);
PAINT ORANGE (-6700 2575);
DISPLAY INVISIBLE (-6700 2575);
FORCEPROP 2 LAST BOM_COST SM_HM
J 2
(-6700 2575);
DISPLAY 1.021277 (-6700 2575);
PAINT ORANGE (-6700 2575);
DISPLAY INVISIBLE (-6700 2575);
FORCEPROP 1 LASTPIN (-6650 2250) $PN 2
J 2
(-6655 2260);
DISPLAY 0.787234 (-6655 2260);
PAINT ORANGE (-6655 2260);
DISPLAY INVISIBLE (-6655 2260);
FORCEPROP 1 LASTPIN (-6650 2450) $PN 1
J 2
(-6655 2412);
DISPLAY 0.787234 (-6655 2412);
PAINT ORANGE (-6655 2412);
DISPLAY INVISIBLE (-6655 2412);
FORCEPROP 2 LAST CDS_LIB mstr_discrete
J 2
(-6650 2350);
PAINT ORANGE (-6650 2350);
DISPLAY INVISIBLE (-6650 2350);
FORCEADD RES..2
(-6275 2850);
FORCEPROP 1 LAST TOLERANCE 1%
J 0
(-6230 2875);
DISPLAY 0.617021 (-6230 2875);
PAINT SKYBLUE (-6230 2875);
FORCEPROP 1 LAST WATTAGE 1/16W
J 0
(-6235 2825);
DISPLAY 0.617021 (-6235 2825);
PAINT SKYBLUE (-6235 2825);
FORCEPROP 1 LAST PACK_TYPE 0402
J 0
(-6235 2675);
DISPLAY 0.617021 (-6235 2675);
PAINT SKYBLUE (-6235 2675);
FORCEPROP 1 LAST VALUE 4.75K
J 0
(-6230 2925);
DISPLAY 0.617021 (-6230 2925);
PAINT SKYBLUE (-6230 2925);
FORCEPROP 1 LAST PART_NUMBER G21796-072
J 0
(-6235 2725);
DISPLAY 0.617021 (-6235 2725);
PAINT BLUE (-6235 2725);
FORCEPROP 1 LAST LOCATION R9G23
J 0
(-6230 2975);
DISPLAY 0.617021 (-6230 2975);
PAINT AQUA (-6230 2975);
FORCEPROP 1 LAST MATERIAL EMPTY
J 0
(-6235 2775);
DISPLAY 0.617021 (-6235 2775);
PAINT RED (-6235 2775);
FORCEPROP 1 LASTPIN (-6275 2750) $PN 2
J 0
(-6270 2760);
DISPLAY 0.787234 (-6270 2760);
PAINT ORANGE (-6270 2760);
DISPLAY INVISIBLE (-6270 2760);
FORCEPROP 2 LAST CDS_LIB mstr_discrete
J 0
(-6275 2850);
PAINT ORANGE (-6275 2850);
DISPLAY INVISIBLE (-6275 2850);
FORCEPROP 1 LASTPIN (-6275 2950) $PN 1
J 0
(-6270 2912);
DISPLAY 0.787234 (-6270 2912);
PAINT ORANGE (-6270 2912);
DISPLAY INVISIBLE (-6270 2912);
FORCEPROP 2 LAST ROOM HEC_VOLT_MONITOR
J 0
(-6225 3025);
DISPLAY 1.021277 (-6225 3025);
PAINT ORANGE (-6225 3025);
DISPLAY INVISIBLE (-6225 3025);
FORCEPROP 1 LAST PATH I57
J 0
(-6225 3025);
DISPLAY 0.978723 (-6225 3025);
PAINT WHITE (-6225 3025);
DISPLAY INVISIBLE (-6225 3025);
FORCEPROP 2 LAST CDS_LOCATION R9G23
J 0
(-6230 2975);
DISPLAY 0.617021 (-6230 2975);
PAINT AQUA (-6230 2975);
DISPLAY INVISIBLE (-6230 2975);
FORCEPROP 2 LAST BOM_COST SM_HM
J 0
(-6225 3075);
DISPLAY 1.021277 (-6225 3075);
PAINT ORANGE (-6225 3075);
DISPLAY INVISIBLE (-6225 3075);
FORCEPROP 2 LAST CDS_SEC 1
J 0
(-6225 3075);
DISPLAY 1.021277 (-6225 3075);
PAINT ORANGE (-6225 3075);
DISPLAY INVISIBLE (-6225 3075);
FORCEPROP 2 LAST $SEC 1
J 0
(-6225 3075);
DISPLAY 0.680851 (-6225 3075);
PAINT MONO (-6225 3075);
DISPLAY INVISIBLE (-6225 3075);
FORCEADD RES..2
(-6650 2850);
FORCEPROP 1 LAST PACK_TYPE 0402
J 0
(-6610 2675);
DISPLAY 0.617021 (-6610 2675);
PAINT SKYBLUE (-6610 2675);
FORCEPROP 1 LAST MATERIAL EMPTY
J 0
(-6610 2775);
DISPLAY 0.617021 (-6610 2775);
PAINT RED (-6610 2775);
FORCEPROP 1 LAST TOLERANCE 1%
J 0
(-6605 2875);
DISPLAY 0.617021 (-6605 2875);
PAINT SKYBLUE (-6605 2875);
FORCEPROP 1 LAST WATTAGE 1/16W
J 0
(-6610 2825);
DISPLAY 0.617021 (-6610 2825);
PAINT SKYBLUE (-6610 2825);
FORCEPROP 1 LAST VALUE 4.75K
J 0
(-6605 2925);
DISPLAY 0.617021 (-6605 2925);
PAINT SKYBLUE (-6605 2925);
FORCEPROP 1 LAST LOCATION R9G25
J 0
(-6605 2975);
DISPLAY 0.617021 (-6605 2975);
PAINT AQUA (-6605 2975);
FORCEPROP 1 LAST PART_NUMBER G21796-072
J 0
(-6610 2725);
DISPLAY 0.617021 (-6610 2725);
PAINT BLUE (-6610 2725);
FORCEPROP 1 LASTPIN (-6650 2750) $PN 2
J 0
(-6645 2760);
DISPLAY 0.787234 (-6645 2760);
PAINT ORANGE (-6645 2760);
DISPLAY INVISIBLE (-6645 2760);
FORCEPROP 2 LAST CDS_LIB mstr_discrete
J 0
(-6650 2850);
PAINT ORANGE (-6650 2850);
DISPLAY INVISIBLE (-6650 2850);
FORCEPROP 1 LASTPIN (-6650 2950) $PN 1
J 0
(-6645 2912);
DISPLAY 0.787234 (-6645 2912);
PAINT ORANGE (-6645 2912);
DISPLAY INVISIBLE (-6645 2912);
FORCEPROP 2 LAST ROOM HEC_VOLT_MONITOR
J 0
(-6600 3025);
DISPLAY 1.021277 (-6600 3025);
PAINT ORANGE (-6600 3025);
DISPLAY INVISIBLE (-6600 3025);
FORCEPROP 1 LAST PATH I58
J 0
(-6600 3025);
DISPLAY 0.978723 (-6600 3025);
PAINT WHITE (-6600 3025);
DISPLAY INVISIBLE (-6600 3025);
FORCEPROP 2 LAST CDS_LOCATION R9G25
J 0
(-6605 2975);
DISPLAY 0.617021 (-6605 2975);
PAINT AQUA (-6605 2975);
DISPLAY INVISIBLE (-6605 2975);
FORCEPROP 2 LAST BOM_COST SM_HM
J 0
(-6600 3075);
DISPLAY 1.021277 (-6600 3075);
PAINT ORANGE (-6600 3075);
DISPLAY INVISIBLE (-6600 3075);
FORCEPROP 2 LAST CDS_SEC 1
J 0
(-6600 3075);
DISPLAY 1.021277 (-6600 3075);
PAINT ORANGE (-6600 3075);
DISPLAY INVISIBLE (-6600 3075);
FORCEPROP 2 LAST $SEC 1
J 0
(-6600 3075);
DISPLAY 0.680851 (-6600 3075);
PAINT MONO (-6600 3075);
DISPLAY INVISIBLE (-6600 3075);
FORCEADD GND..1
(-6275 2100);
FORCEPROP 3 LASTPIN (-6275 2150) SIG_NAME GND\g
J 0
(-6265 2160);
DISPLAY 0.659574 (-6265 2160);
PAINT MONO (-6265 2160);
DISPLAY INVISIBLE (-6265 2160);
FORCEPROP 1 LAST VOLTAGE 0.0V
J 0
(-6320 2057);
DISPLAY 0.340426 (-6320 2057);
PAINT SKYBLUE (-6320 2057);
DISPLAY INVISIBLE (-6320 2057);
FORCEPROP 2 LAST CDS_LIB mstr_symbols
J 0
(-6275 2100);
PAINT ORANGE (-6275 2100);
DISPLAY INVISIBLE (-6275 2100);
FORCEPROP 1 LAST BODY_TYPE PLUMBING
J 0
(-6320 2057);
DISPLAY 0.340426 (-6320 2057);
PAINT GREEN (-6320 2057);
DISPLAY INVISIBLE (-6320 2057);
FORCEPROP 1 LAST HDL_POWER GND
J 0
(-6275 2250);
DISPLAY 0.872340 (-6275 2250);
PAINT GREEN (-6275 2250);
DISPLAY INVISIBLE (-6275 2250);
FORCEPROP 1 LAST SIZE 1B
J 0
(-6200 2050);
DISPLAY 0.872340 (-6200 2050);
PAINT AQUA (-6200 2050);
DISPLAY INVISIBLE (-6200 2050);
FORCEPROP 1 LAST PATH I59
J 0
(-6200 2100);
DISPLAY 0.872340 (-6200 2100);
PAINT AQUA (-6200 2100);
DISPLAY INVISIBLE (-6200 2100);
FORCEADD GND..1
(-6650 2100);
FORCEPROP 3 LASTPIN (-6650 2150) SIG_NAME GND\g
J 0
(-6640 2160);
DISPLAY 0.659574 (-6640 2160);
PAINT MONO (-6640 2160);
DISPLAY INVISIBLE (-6640 2160);
FORCEPROP 1 LAST BODY_TYPE PLUMBING
J 0
(-6695 2057);
DISPLAY 0.340426 (-6695 2057);
PAINT GREEN (-6695 2057);
DISPLAY INVISIBLE (-6695 2057);
FORCEPROP 1 LAST VOLTAGE 0.0V
J 0
(-6695 2057);
DISPLAY 0.340426 (-6695 2057);
PAINT SKYBLUE (-6695 2057);
DISPLAY INVISIBLE (-6695 2057);
FORCEPROP 1 LAST SIZE 1B
J 0
(-6575 2050);
DISPLAY 0.872340 (-6575 2050);
PAINT AQUA (-6575 2050);
DISPLAY INVISIBLE (-6575 2050);
FORCEPROP 2 LAST CDS_LIB mstr_symbols
J 0
(-6650 2100);
PAINT ORANGE (-6650 2100);
DISPLAY INVISIBLE (-6650 2100);
FORCEPROP 1 LAST PATH I60
J 0
(-6575 2100);
DISPLAY 0.872340 (-6575 2100);
PAINT AQUA (-6575 2100);
DISPLAY INVISIBLE (-6575 2100);
FORCEPROP 1 LAST HDL_POWER GND
J 0
(-6650 2250);
DISPLAY 0.872340 (-6650 2250);
PAINT GREEN (-6650 2250);
DISPLAY INVISIBLE (-6650 2250);
FORCEADD CAP_A..1
(-5050 3525);
FORCEPROP 1 LAST MATERIAL X7R
J 0
(-5000 3425);
DISPLAY 0.617021 (-5000 3425);
PAINT SKYBLUE (-5000 3425);
FORCEPROP 1 LAST VOLTAGE 16V
J 0
(-5000 3525);
DISPLAY 0.617021 (-5000 3525);
PAINT SKYBLUE (-5000 3525);
FORCEPROP 1 LAST TOLERANCE 10%
J 0
(-5000 3475);
DISPLAY 0.617021 (-5000 3475);
PAINT SKYBLUE (-5000 3475);
FORCEPROP 1 LAST PACK_TYPE 0402V
J 0
(-5000 3325);
DISPLAY 0.617021 (-5000 3325);
PAINT SKYBLUE (-5000 3325);
FORCEPROP 1 LAST PART_NUMBER A36096-030
J 0
(-5000 3375);
DISPLAY 0.617021 (-5000 3375);
PAINT BLUE (-5000 3375);
FORCEPROP 1 LAST VALUE 0.1UF
J 0
(-5000 3575);
DISPLAY 0.617021 (-5000 3575);
PAINT SKYBLUE (-5000 3575);
FORCEPROP 1 LAST LOCATION C9G19
J 0
(-5000 3625);
DISPLAY 0.617021 (-5000 3625);
PAINT AQUA (-5000 3625);
FORCEPROP 1 LASTPIN (-5050 3425) $PN 2
J 0
(-5040 3405);
DISPLAY 0.787234 (-5040 3405);
PAINT ORANGE (-5040 3405);
DISPLAY INVISIBLE (-5040 3405);
FORCEPROP 2 LAST CDS_LIB dev_discrete
J 0
(-5050 3525);
PAINT ORANGE (-5050 3525);
DISPLAY INVISIBLE (-5050 3525);
FORCEPROP 1 LASTPIN (-5050 3625) $PN 1
J 0
(-5040 3605);
DISPLAY 0.787234 (-5040 3605);
PAINT ORANGE (-5040 3605);
DISPLAY INVISIBLE (-5040 3605);
FORCEPROP 2 LAST CDS_LOCATION C9G19
J 0
(-5000 3625);
DISPLAY 0.617021 (-5000 3625);
PAINT AQUA (-5000 3625);
DISPLAY INVISIBLE (-5000 3625);
FORCEPROP 2 LAST ROOM HEC_VOLT_MONITOR
J 0
(-5000 3675);
DISPLAY 1.021277 (-5000 3675);
PAINT ORANGE (-5000 3675);
DISPLAY INVISIBLE (-5000 3675);
FORCEPROP 1 LAST PATH I61
J 0
(-5000 3675);
DISPLAY 0.978723 (-5000 3675);
PAINT WHITE (-5000 3675);
DISPLAY INVISIBLE (-5000 3675);
FORCEPROP 2 LAST $SEC 1
J 0
(-5000 3725);
DISPLAY 0.680851 (-5000 3725);
PAINT MONO (-5000 3725);
DISPLAY INVISIBLE (-5000 3725);
FORCEPROP 2 LAST CDS_SEC 1
J 0
(-5000 3725);
DISPLAY 1.021277 (-5000 3725);
PAINT ORANGE (-5000 3725);
DISPLAY INVISIBLE (-5000 3725);
FORCEPROP 2 LAST BOM_COST SM_HM
J 0
(-5000 3725);
DISPLAY 1.021277 (-5000 3725);
PAINT ORANGE (-5000 3725);
DISPLAY INVISIBLE (-5000 3725);
FORCEADD GND..1
(-5050 3250);
FORCEPROP 3 LASTPIN (-5050 3300) SIG_NAME GND\g
J 0
(-5040 3310);
DISPLAY 0.659574 (-5040 3310);
PAINT MONO (-5040 3310);
DISPLAY INVISIBLE (-5040 3310);
FORCEPROP 1 LAST PATH I62
J 0
(-4975 3250);
DISPLAY 0.872340 (-4975 3250);
PAINT AQUA (-4975 3250);
DISPLAY INVISIBLE (-4975 3250);
FORCEPROP 1 LAST BODY_TYPE PLUMBING
J 0
(-5095 3207);
DISPLAY 0.340426 (-5095 3207);
PAINT GREEN (-5095 3207);
DISPLAY INVISIBLE (-5095 3207);
FORCEPROP 2 LAST CDS_LIB mstr_symbols
J 0
(-5050 3250);
PAINT ORANGE (-5050 3250);
DISPLAY INVISIBLE (-5050 3250);
FORCEPROP 1 LAST SIZE 1B
J 0
(-4975 3200);
DISPLAY 0.872340 (-4975 3200);
PAINT AQUA (-4975 3200);
DISPLAY INVISIBLE (-4975 3200);
FORCEPROP 1 LAST VOLTAGE 0.0V
J 0
(-5095 3207);
DISPLAY 0.340426 (-5095 3207);
PAINT SKYBLUE (-5095 3207);
DISPLAY INVISIBLE (-5095 3207);
FORCEPROP 1 LAST HDL_POWER GND
J 0
(-5050 3400);
DISPLAY 0.872340 (-5050 3400);
PAINT GREEN (-5050 3400);
DISPLAY INVISIBLE (-5050 3400);
FORCEADD P3V3_STBY..1
(-5750 3950);
FORCEPROP 3 LASTPIN (-5750 3900) SIG_NAME P3V3_STBY\g
J 0
(-5740 3910);
DISPLAY 0.659574 (-5740 3910);
PAINT MONO (-5740 3910);
DISPLAY INVISIBLE (-5740 3910);
FORCEPROP 1 LAST HDL_POWER P3V3_STBY
J 0
(-6050 3825);
DISPLAY 0.872340 (-6050 3825);
PAINT ORANGE (-6050 3825);
DISPLAY INVISIBLE (-6050 3825);
FORCEPROP 1 LAST PATH I63
J 0
(-5705 3952);
DISPLAY 0.340426 (-5705 3952);
PAINT GREEN (-5705 3952);
DISPLAY INVISIBLE (-5705 3952);
FORCEPROP 1 LAST BODY_TYPE PLUMBING
J 0
(-5795 3907);
DISPLAY 0.340426 (-5795 3907);
PAINT GREEN (-5795 3907);
DISPLAY INVISIBLE (-5795 3907);
FORCEPROP 1 LAST SIZE 1B
J 0
(-5705 3972);
DISPLAY 0.340426 (-5705 3972);
PAINT GREEN (-5705 3972);
DISPLAY INVISIBLE (-5705 3972);
FORCEPROP 2 LAST CDS_LIB mstr_symbols
J 0
(-5750 3950);
PAINT ORANGE (-5750 3950);
DISPLAY INVISIBLE (-5750 3950);
FORCEPROP 1 LAST VOLTAGE 3.3V
J 0
(-5795 3907);
DISPLAY 0.340426 (-5795 3907);
PAINT SKYBLUE (-5795 3907);
DISPLAY INVISIBLE (-5795 3907);
FORCEADD P3V3_STBY..1
(-6275 3100);
FORCEPROP 3 LASTPIN (-6275 3050) SIG_NAME P3V3_STBY\g
J 0
(-6265 3060);
DISPLAY 0.659574 (-6265 3060);
PAINT MONO (-6265 3060);
DISPLAY INVISIBLE (-6265 3060);
FORCEPROP 1 LAST HDL_POWER P3V3_STBY
J 0
(-6575 2975);
DISPLAY 0.872340 (-6575 2975);
PAINT ORANGE (-6575 2975);
DISPLAY INVISIBLE (-6575 2975);
FORCEPROP 1 LAST BODY_TYPE PLUMBING
J 0
(-6320 3057);
DISPLAY 0.340426 (-6320 3057);
PAINT GREEN (-6320 3057);
DISPLAY INVISIBLE (-6320 3057);
FORCEPROP 1 LAST VOLTAGE 3.3V
J 0
(-6320 3057);
DISPLAY 0.340426 (-6320 3057);
PAINT SKYBLUE (-6320 3057);
DISPLAY INVISIBLE (-6320 3057);
FORCEPROP 2 LAST CDS_LIB mstr_symbols
J 0
(-6275 3100);
PAINT ORANGE (-6275 3100);
DISPLAY INVISIBLE (-6275 3100);
FORCEPROP 1 LAST SIZE 1B
J 0
(-6230 3122);
DISPLAY 0.340426 (-6230 3122);
PAINT GREEN (-6230 3122);
DISPLAY INVISIBLE (-6230 3122);
FORCEPROP 1 LAST PATH I64
J 0
(-6230 3102);
DISPLAY 0.340426 (-6230 3102);
PAINT GREEN (-6230 3102);
DISPLAY INVISIBLE (-6230 3102);
FORCEADD P3V3_STBY..1
(-6650 3100);
FORCEPROP 3 LASTPIN (-6650 3050) SIG_NAME P3V3_STBY\g
J 0
(-6640 3060);
DISPLAY 0.659574 (-6640 3060);
PAINT MONO (-6640 3060);
DISPLAY INVISIBLE (-6640 3060);
FORCEPROP 1 LAST HDL_POWER P3V3_STBY
J 0
(-6950 2975);
DISPLAY 0.872340 (-6950 2975);
PAINT ORANGE (-6950 2975);
DISPLAY INVISIBLE (-6950 2975);
FORCEPROP 1 LAST BODY_TYPE PLUMBING
J 0
(-6695 3057);
DISPLAY 0.340426 (-6695 3057);
PAINT GREEN (-6695 3057);
DISPLAY INVISIBLE (-6695 3057);
FORCEPROP 1 LAST VOLTAGE 3.3V
J 0
(-6695 3057);
DISPLAY 0.340426 (-6695 3057);
PAINT SKYBLUE (-6695 3057);
DISPLAY INVISIBLE (-6695 3057);
FORCEPROP 1 LAST SIZE 1B
J 0
(-6605 3122);
DISPLAY 0.340426 (-6605 3122);
PAINT GREEN (-6605 3122);
DISPLAY INVISIBLE (-6605 3122);
FORCEPROP 2 LAST CDS_LIB mstr_symbols
J 0
(-6650 3100);
PAINT ORANGE (-6650 3100);
DISPLAY INVISIBLE (-6650 3100);
FORCEPROP 1 LAST PATH I65
J 0
(-6605 3102);
DISPLAY 0.340426 (-6605 3102);
PAINT GREEN (-6605 3102);
DISPLAY INVISIBLE (-6605 3102);
FORCEADD GND..1
(-3925 1900);
FORCEPROP 3 LASTPIN (-3925 1950) SIG_NAME GND\g
J 0
(-3915 1960);
DISPLAY 0.659574 (-3915 1960);
PAINT MONO (-3915 1960);
DISPLAY INVISIBLE (-3915 1960);
FORCEPROP 1 LAST PATH I66
J 0
(-3850 1900);
DISPLAY 0.872340 (-3850 1900);
PAINT AQUA (-3850 1900);
DISPLAY INVISIBLE (-3850 1900);
FORCEPROP 1 LAST BODY_TYPE PLUMBING
J 0
(-3970 1857);
DISPLAY 0.340426 (-3970 1857);
PAINT GREEN (-3970 1857);
DISPLAY INVISIBLE (-3970 1857);
FORCEPROP 1 LAST VOLTAGE 0.0V
J 0
(-3970 1857);
DISPLAY 0.340426 (-3970 1857);
PAINT SKYBLUE (-3970 1857);
DISPLAY INVISIBLE (-3970 1857);
FORCEPROP 2 LAST CDS_LIB mstr_symbols
J 0
(-3925 1900);
PAINT ORANGE (-3925 1900);
DISPLAY INVISIBLE (-3925 1900);
FORCEPROP 1 LAST SIZE 1B
J 0
(-3850 1850);
DISPLAY 0.872340 (-3850 1850);
PAINT AQUA (-3850 1850);
DISPLAY INVISIBLE (-3850 1850);
FORCEPROP 1 LAST HDL_POWER GND
J 0
(-3925 2050);
DISPLAY 0.872340 (-3925 2050);
PAINT GREEN (-3925 2050);
DISPLAY INVISIBLE (-3925 2050);
FORCEADD CAP..1
(-5325 3525);
FORCEPROP 1 LAST PACK_TYPE 0805
J 0
(-5275 3325);
DISPLAY 0.617021 (-5275 3325);
PAINT SKYBLUE (-5275 3325);
FORCEPROP 1 LAST MATERIAL X7R
J 0
(-5275 3425);
DISPLAY 0.617021 (-5275 3425);
PAINT SKYBLUE (-5275 3425);
FORCEPROP 1 LAST VOLTAGE 16V
J 0
(-5275 3525);
DISPLAY 0.617021 (-5275 3525);
PAINT SKYBLUE (-5275 3525);
FORCEPROP 1 LAST TOLERANCE 10%
J 0
(-5275 3475);
DISPLAY 0.617021 (-5275 3475);
PAINT SKYBLUE (-5275 3475);
FORCEPROP 1 LAST VALUE 10UF
J 0
(-5275 3575);
DISPLAY 0.617021 (-5275 3575);
PAINT SKYBLUE (-5275 3575);
FORCEPROP 1 LAST LOCATION C1U20
J 0
(-5275 3625);
DISPLAY 0.617021 (-5275 3625);
PAINT AQUA (-5275 3625);
FORCEPROP 1 LAST PART_NUMBER G10601-001
J 0
(-5275 3375);
DISPLAY 0.617021 (-5275 3375);
PAINT BLUE (-5275 3375);
FORCEPROP 1 LASTPIN (-5325 3425) $PN 2
J 0
(-5315 3405);
DISPLAY 0.787234 (-5315 3405);
PAINT ORANGE (-5315 3405);
DISPLAY INVISIBLE (-5315 3405);
FORCEPROP 2 LAST CDS_LIB mstr_discrete
J 0
(-5325 3525);
PAINT ORANGE (-5325 3525);
DISPLAY INVISIBLE (-5325 3525);
FORCEPROP 2 LAST CDS_LOCATION C1U20
J 0
(-5275 3625);
DISPLAY 0.617021 (-5275 3625);
PAINT AQUA (-5275 3625);
DISPLAY INVISIBLE (-5275 3625);
FORCEPROP 1 LASTPIN (-5325 3625) $PN 1
J 0
(-5315 3605);
DISPLAY 0.787234 (-5315 3605);
PAINT ORANGE (-5315 3605);
DISPLAY INVISIBLE (-5315 3605);
FORCEPROP 1 LAST PATH I67
J 0
(-5275 3675);
DISPLAY 0.978723 (-5275 3675);
PAINT WHITE (-5275 3675);
DISPLAY INVISIBLE (-5275 3675);
FORCEPROP 2 LAST ROOM HEC_VOLT_MONITOR
J 0
(-5275 3675);
DISPLAY 1.021277 (-5275 3675);
PAINT ORANGE (-5275 3675);
DISPLAY INVISIBLE (-5275 3675);
FORCEPROP 2 LAST BOM_COST SM_HM
J 0
(-5275 3725);
DISPLAY 1.021277 (-5275 3725);
PAINT ORANGE (-5275 3725);
DISPLAY INVISIBLE (-5275 3725);
FORCEPROP 2 LAST CDS_SEC 1
J 0
(-5275 3725);
DISPLAY 1.021277 (-5275 3725);
PAINT ORANGE (-5275 3725);
DISPLAY INVISIBLE (-5275 3725);
FORCEPROP 2 LAST $SEC 1
J 0
(-5275 3725);
DISPLAY 0.680851 (-5275 3725);
PAINT MONO (-5275 3725);
DISPLAY INVISIBLE (-5275 3725);
FORCEADD GND..1
(-5325 3250);
FORCEPROP 3 LASTPIN (-5325 3300) SIG_NAME GND\g
J 0
(-5315 3310);
DISPLAY 0.659574 (-5315 3310);
PAINT MONO (-5315 3310);
DISPLAY INVISIBLE (-5315 3310);
FORCEPROP 1 LAST PATH I68
J 0
(-5250 3250);
DISPLAY 0.872340 (-5250 3250);
PAINT AQUA (-5250 3250);
DISPLAY INVISIBLE (-5250 3250);
FORCEPROP 1 LAST BODY_TYPE PLUMBING
J 0
(-5370 3207);
DISPLAY 0.340426 (-5370 3207);
PAINT GREEN (-5370 3207);
DISPLAY INVISIBLE (-5370 3207);
FORCEPROP 1 LAST SIZE 1B
J 0
(-5250 3200);
DISPLAY 0.872340 (-5250 3200);
PAINT AQUA (-5250 3200);
DISPLAY INVISIBLE (-5250 3200);
FORCEPROP 2 LAST CDS_LIB mstr_symbols
J 0
(-5325 3250);
PAINT ORANGE (-5325 3250);
DISPLAY INVISIBLE (-5325 3250);
FORCEPROP 1 LAST VOLTAGE 0.0V
J 0
(-5370 3207);
DISPLAY 0.340426 (-5370 3207);
PAINT SKYBLUE (-5370 3207);
DISPLAY INVISIBLE (-5370 3207);
FORCEPROP 1 LAST HDL_POWER GND
J 0
(-5325 3400);
DISPLAY 0.872340 (-5325 3400);
PAINT GREEN (-5325 3400);
DISPLAY INVISIBLE (-5325 3400);
FORCEADD RES..2
(-3650 3375);
FORCEPROP 1 LASTPIN (-3650 3275) $PN 2
J 0
(-3645 3285);
DISPLAY 0.617021 (-3645 3285);
PAINT ORANGE (-3645 3285);
FORCEPROP 1 LASTPIN (-3650 3475) $PN 1
J 0
(-3645 3437);
DISPLAY 0.617021 (-3645 3437);
PAINT ORANGE (-3645 3437);
FORCEPROP 1 LAST WATTAGE 1/16W
J 0
(-3610 3350);
DISPLAY 0.617021 (-3610 3350);
PAINT SKYBLUE (-3610 3350);
FORCEPROP 1 LAST MATERIAL CHIP
J 0
(-3610 3300);
DISPLAY 0.617021 (-3610 3300);
PAINT SKYBLUE (-3610 3300);
FORCEPROP 1 LAST PACK_TYPE 0402
J 0
(-3610 3200);
DISPLAY 0.617021 (-3610 3200);
PAINT SKYBLUE (-3610 3200);
FORCEPROP 1 LAST TOLERANCE 1%
J 0
(-3605 3400);
DISPLAY 0.617021 (-3605 3400);
PAINT SKYBLUE (-3605 3400);
FORCEPROP 1 LAST VALUE 4.75K
J 0
(-3605 3450);
DISPLAY 0.617021 (-3605 3450);
PAINT SKYBLUE (-3605 3450);
FORCEPROP 1 LAST PART_NUMBER G21796-072
J 0
(-3610 3250);
DISPLAY 0.617021 (-3610 3250);
PAINT BLUE (-3610 3250);
FORCEPROP 1 LAST LOCATION R9G21
J 0
(-3605 3500);
DISPLAY 0.617021 (-3605 3500);
PAINT AQUA (-3605 3500);
FORCEPROP 2 LAST CDS_LOCATION R9G21
J 0
(-3605 3500);
DISPLAY 0.617021 (-3605 3500);
PAINT AQUA (-3605 3500);
DISPLAY INVISIBLE (-3605 3500);
FORCEPROP 2 LAST CDS_LIB mstr_discrete
J 0
(-3650 3375);
PAINT ORANGE (-3650 3375);
DISPLAY INVISIBLE (-3650 3375);
FORCEPROP 2 LAST ROOM HEC_VOLT_MONITOR
J 0
(-3600 3550);
DISPLAY 1.021277 (-3600 3550);
PAINT ORANGE (-3600 3550);
DISPLAY INVISIBLE (-3600 3550);
FORCEPROP 1 LAST PATH I69
J 0
(-3600 3550);
DISPLAY 0.978723 (-3600 3550);
PAINT WHITE (-3600 3550);
DISPLAY INVISIBLE (-3600 3550);
FORCEPROP 2 LAST SEC 1
J 0
(-3600 3600);
DISPLAY 0.680851 (-3600 3600);
PAINT MONO (-3600 3600);
DISPLAY INVISIBLE (-3600 3600);
FORCEPROP 2 LAST SEC_TYPE 0402
J 0
(-3600 3600);
DISPLAY 1.021277 (-3600 3600);
PAINT ORANGE (-3600 3600);
DISPLAY INVISIBLE (-3600 3600);
FORCEPROP 2 LAST BOM_COST SM_HM
J 0
(-3600 3600);
DISPLAY 1.021277 (-3600 3600);
PAINT ORANGE (-3600 3600);
DISPLAY INVISIBLE (-3600 3600);
FORCEADD P3V3_STBY..1
(-3650 3725);
FORCEPROP 3 LASTPIN (-3650 3675) SIG_NAME P3V3_STBY\g
J 0
(-3640 3685);
DISPLAY 0.659574 (-3640 3685);
PAINT MONO (-3640 3685);
DISPLAY INVISIBLE (-3640 3685);
FORCEPROP 1 LAST HDL_POWER P3V3_STBY
J 0
(-3950 3600);
DISPLAY 0.872340 (-3950 3600);
PAINT ORANGE (-3950 3600);
DISPLAY INVISIBLE (-3950 3600);
FORCEPROP 1 LAST PATH I70
J 0
(-3605 3727);
DISPLAY 0.340426 (-3605 3727);
PAINT GREEN (-3605 3727);
DISPLAY INVISIBLE (-3605 3727);
FORCEPROP 1 LAST BODY_TYPE PLUMBING
J 0
(-3695 3682);
DISPLAY 0.340426 (-3695 3682);
PAINT GREEN (-3695 3682);
DISPLAY INVISIBLE (-3695 3682);
FORCEPROP 1 LAST SIZE 1B
J 0
(-3605 3747);
DISPLAY 0.340426 (-3605 3747);
PAINT GREEN (-3605 3747);
DISPLAY INVISIBLE (-3605 3747);
FORCEPROP 2 LAST CDS_LIB mstr_symbols
J 0
(-3650 3725);
PAINT ORANGE (-3650 3725);
DISPLAY INVISIBLE (-3650 3725);
FORCEPROP 1 LAST VOLTAGE 3.3V
J 0
(-3695 3682);
DISPLAY 0.340426 (-3695 3682);
PAINT SKYBLUE (-3695 3682);
DISPLAY INVISIBLE (-3695 3682);
FORCEADD OFFPAGE..1
(-5650 2525);
FORCEPROP 2 LAST $XR0 169 
J 0
(-5902 2525);
DISPLAY 0.638298 (-5902 2525);
PAINT MONO (-5902 2525);
FORCEPROP 2 LAST $XR1 147 
J 0
(-6022 2525);
DISPLAY 0.638298 (-6022 2525);
PAINT MONO (-6022 2525);
FORCEPROP 2 LAST CDS_LIB mstr_standard
J 0
(-5650 2525);
PAINT ORANGE (-5650 2525);
DISPLAY INVISIBLE (-5650 2525);
FORCEPROP 1 LAST COMMENT_BODY TRUE
J 0
(-5525 2425);
DISPLAY 0.872340 (-5525 2425);
PAINT GREEN (-5525 2425);
DISPLAY INVISIBLE (-5525 2425);
FORCEPROP 1 LAST OFFPAGE TRUE
J 0
(-5325 2400);
DISPLAY 0.872340 (-5325 2400);
PAINT GREEN (-5325 2400);
DISPLAY INVISIBLE (-5325 2400);
FORCEPROP 2 LAST PATH I71
J 0
(-5600 2600);
DISPLAY 1.021277 (-5600 2600);
PAINT ORANGE (-5600 2600);
DISPLAY INVISIBLE (-5600 2600);
FORCEADD OFFPAGE..1
(-5650 2475);
FORCEPROP 2 LAST $XR0 169 
J 0
(-5902 2475);
DISPLAY 0.638298 (-5902 2475);
PAINT MONO (-5902 2475);
FORCEPROP 2 LAST $XR1 147 
J 0
(-6022 2475);
DISPLAY 0.638298 (-6022 2475);
PAINT MONO (-6022 2475);
FORCEPROP 2 LAST CDS_LIB mstr_standard
J 0
(-5650 2475);
PAINT ORANGE (-5650 2475);
DISPLAY INVISIBLE (-5650 2475);
FORCEPROP 1 LAST COMMENT_BODY TRUE
J 0
(-5525 2375);
DISPLAY 0.872340 (-5525 2375);
PAINT GREEN (-5525 2375);
DISPLAY INVISIBLE (-5525 2375);
FORCEPROP 1 LAST OFFPAGE TRUE
J 0
(-5325 2350);
DISPLAY 0.872340 (-5325 2350);
PAINT GREEN (-5325 2350);
DISPLAY INVISIBLE (-5325 2350);
FORCEPROP 2 LAST PATH I72
J 0
(-5600 2550);
DISPLAY 1.021277 (-5600 2550);
PAINT ORANGE (-5600 2550);
DISPLAY INVISIBLE (-5600 2550);
FORCEADD OFFPAGE..1
(-5650 2425);
FORCEPROP 2 LAST $XR0 169 
J 0
(-5902 2425);
DISPLAY 0.638298 (-5902 2425);
PAINT MONO (-5902 2425);
FORCEPROP 2 LAST $XR1 147 
J 0
(-6022 2425);
DISPLAY 0.638298 (-6022 2425);
PAINT MONO (-6022 2425);
FORCEPROP 2 LAST CDS_LIB mstr_standard
J 0
(-5650 2425);
PAINT ORANGE (-5650 2425);
DISPLAY INVISIBLE (-5650 2425);
FORCEPROP 1 LAST COMMENT_BODY TRUE
J 0
(-5525 2325);
DISPLAY 0.872340 (-5525 2325);
PAINT GREEN (-5525 2325);
DISPLAY INVISIBLE (-5525 2325);
FORCEPROP 2 LAST PATH I73
J 0
(-5600 2500);
DISPLAY 1.021277 (-5600 2500);
PAINT ORANGE (-5600 2500);
DISPLAY INVISIBLE (-5600 2500);
FORCEPROP 1 LAST OFFPAGE TRUE
J 0
(-5325 2300);
DISPLAY 0.872340 (-5325 2300);
PAINT GREEN (-5325 2300);
DISPLAY INVISIBLE (-5325 2300);
FORCEADD OFFPAGE..1
(-5650 2375);
FORCEPROP 2 LAST $XR0 169 
J 0
(-5902 2375);
DISPLAY 0.638298 (-5902 2375);
PAINT MONO (-5902 2375);
FORCEPROP 2 LAST $XR1 147 
J 0
(-6022 2375);
DISPLAY 0.638298 (-6022 2375);
PAINT MONO (-6022 2375);
FORCEPROP 2 LAST CDS_LIB mstr_standard
J 0
(-5650 2375);
PAINT ORANGE (-5650 2375);
DISPLAY INVISIBLE (-5650 2375);
FORCEPROP 1 LAST COMMENT_BODY TRUE
J 0
(-5525 2275);
DISPLAY 0.872340 (-5525 2275);
PAINT GREEN (-5525 2275);
DISPLAY INVISIBLE (-5525 2275);
FORCEPROP 2 LAST PATH I74
J 0
(-5600 2450);
DISPLAY 1.021277 (-5600 2450);
PAINT ORANGE (-5600 2450);
DISPLAY INVISIBLE (-5600 2450);
FORCEPROP 1 LAST OFFPAGE TRUE
J 0
(-5325 2250);
DISPLAY 0.872340 (-5325 2250);
PAINT GREEN (-5325 2250);
DISPLAY INVISIBLE (-5325 2250);
FORCEADD OFFPAGE..1
(-5650 2325);
FORCEPROP 2 LAST $XR0 169 
J 0
(-5902 2325);
DISPLAY 0.638298 (-5902 2325);
PAINT MONO (-5902 2325);
FORCEPROP 2 LAST $XR1 147 
J 0
(-6022 2325);
DISPLAY 0.638298 (-6022 2325);
PAINT MONO (-6022 2325);
FORCEPROP 2 LAST CDS_LIB mstr_standard
J 0
(-5650 2325);
PAINT ORANGE (-5650 2325);
DISPLAY INVISIBLE (-5650 2325);
FORCEPROP 1 LAST COMMENT_BODY TRUE
J 0
(-5525 2225);
DISPLAY 0.872340 (-5525 2225);
PAINT GREEN (-5525 2225);
DISPLAY INVISIBLE (-5525 2225);
FORCEPROP 2 LAST PATH I75
J 0
(-5600 2400);
DISPLAY 1.021277 (-5600 2400);
PAINT ORANGE (-5600 2400);
DISPLAY INVISIBLE (-5600 2400);
FORCEPROP 1 LAST OFFPAGE TRUE
J 0
(-5325 2200);
DISPLAY 0.872340 (-5325 2200);
PAINT GREEN (-5325 2200);
DISPLAY INVISIBLE (-5325 2200);
FORCEADD OFFPAGE..1
(-5650 2275);
FORCEPROP 2 LAST $XR0 169 
J 0
(-5902 2275);
DISPLAY 0.638298 (-5902 2275);
PAINT MONO (-5902 2275);
FORCEPROP 2 LAST $XR1 147 
J 0
(-6022 2275);
DISPLAY 0.638298 (-6022 2275);
PAINT MONO (-6022 2275);
FORCEPROP 2 LAST CDS_LIB mstr_standard
J 0
(-5650 2275);
PAINT ORANGE (-5650 2275);
DISPLAY INVISIBLE (-5650 2275);
FORCEPROP 1 LAST COMMENT_BODY TRUE
J 0
(-5525 2175);
DISPLAY 0.872340 (-5525 2175);
PAINT GREEN (-5525 2175);
DISPLAY INVISIBLE (-5525 2175);
FORCEPROP 2 LAST PATH I76
J 0
(-5600 2350);
DISPLAY 1.021277 (-5600 2350);
PAINT ORANGE (-5600 2350);
DISPLAY INVISIBLE (-5600 2350);
FORCEPROP 1 LAST OFFPAGE TRUE
J 0
(-5325 2150);
DISPLAY 0.872340 (-5325 2150);
PAINT GREEN (-5325 2150);
DISPLAY INVISIBLE (-5325 2150);
FORCEADD OFFPAGE..1
(-5650 2225);
FORCEPROP 2 LAST $XR0 169 
J 0
(-5902 2225);
DISPLAY 0.638298 (-5902 2225);
PAINT MONO (-5902 2225);
FORCEPROP 2 LAST $XR1 147 
J 0
(-6022 2225);
DISPLAY 0.638298 (-6022 2225);
PAINT MONO (-6022 2225);
FORCEPROP 2 LAST CDS_LIB mstr_standard
J 0
(-5650 2225);
PAINT ORANGE (-5650 2225);
DISPLAY INVISIBLE (-5650 2225);
FORCEPROP 1 LAST COMMENT_BODY TRUE
J 0
(-5525 2125);
DISPLAY 0.872340 (-5525 2125);
PAINT GREEN (-5525 2125);
DISPLAY INVISIBLE (-5525 2125);
FORCEPROP 2 LAST PATH I77
J 0
(-5600 2300);
DISPLAY 1.021277 (-5600 2300);
PAINT ORANGE (-5600 2300);
DISPLAY INVISIBLE (-5600 2300);
FORCEPROP 1 LAST OFFPAGE TRUE
J 0
(-5325 2100);
DISPLAY 0.872340 (-5325 2100);
PAINT GREEN (-5325 2100);
DISPLAY INVISIBLE (-5325 2100);
FORCEADD OFFPAGE..1
(-5650 2175);
FORCEPROP 2 LAST $XR0 169 
J 0
(-5902 2175);
DISPLAY 0.638298 (-5902 2175);
PAINT MONO (-5902 2175);
FORCEPROP 2 LAST $XR1 147 
J 0
(-6022 2175);
DISPLAY 0.638298 (-6022 2175);
PAINT MONO (-6022 2175);
FORCEPROP 2 LAST CDS_LIB mstr_standard
J 0
(-5650 2175);
PAINT ORANGE (-5650 2175);
DISPLAY INVISIBLE (-5650 2175);
FORCEPROP 1 LAST COMMENT_BODY TRUE
J 0
(-5525 2075);
DISPLAY 0.872340 (-5525 2075);
PAINT GREEN (-5525 2075);
DISPLAY INVISIBLE (-5525 2075);
FORCEPROP 2 LAST PATH I78
J 0
(-5600 2250);
DISPLAY 1.021277 (-5600 2250);
PAINT ORANGE (-5600 2250);
DISPLAY INVISIBLE (-5600 2250);
FORCEPROP 1 LAST OFFPAGE TRUE
J 0
(-5325 2050);
DISPLAY 0.872340 (-5325 2050);
PAINT GREEN (-5325 2050);
DISPLAY INVISIBLE (-5325 2050);
FORCEADD FERRITE..1
(-5525 3750);
FORCEPROP 1 LAST VALUE 60
J 2
(-5595 3650);
DISPLAY 0.617021 (-5595 3650);
PAINT SKYBLUE (-5595 3650);
FORCEPROP 1 LASTPIN (-5625 3750) $PN 1
J 2
(-5590 3760);
DISPLAY 0.617021 (-5590 3760);
PAINT WHITE (-5590 3760);
FORCEPROP 1 LAST MATERIAL FB
J 0
(-5545 3650);
DISPLAY 0.617021 (-5545 3650);
PAINT SKYBLUE (-5545 3650);
FORCEPROP 1 LAST LOCATION FB1U2
J 0
(-5620 3805);
DISPLAY 0.617021 (-5620 3805);
PAINT AQUA (-5620 3805);
FORCEPROP 1 LASTPIN (-5425 3750) $PN 2
J 0
(-5445 3760);
DISPLAY 0.617021 (-5445 3760);
PAINT WHITE (-5445 3760);
FORCEPROP 1 LAST PART_NUMBER 693286-001
J 0
(-5620 3865);
DISPLAY 0.617021 (-5620 3865);
PAINT BLUE (-5620 3865);
FORCEPROP 1 LAST PACK_TYPE SMLF
J 0
(-5470 3700);
DISPLAY 0.617021 (-5470 3700);
PAINT SKYBLUE (-5470 3700);
FORCEPROP 2 LAST CDS_LIB mstr_discrete
J 0
(-5525 3750);
PAINT MONO (-5525 3750);
DISPLAY INVISIBLE (-5525 3750);
FORCEPROP 2 LAST CDS_LOCATION FB1U2
J 0
(-5620 3805);
DISPLAY 0.617021 (-5620 3805);
PAINT AQUA (-5620 3805);
DISPLAY INVISIBLE (-5620 3805);
FORCEPROP 2 LAST BOM_COST SM_HM
J 0
(-5600 3950);
DISPLAY 1.021277 (-5600 3950);
PAINT ORANGE (-5600 3950);
DISPLAY INVISIBLE (-5600 3950);
FORCEPROP 2 LAST SEC_TYPE SMLF
J 0
(-5600 3975);
DISPLAY 1.382979 (-5600 3975);
PAINT ORANGE (-5600 3975);
DISPLAY INVISIBLE (-5600 3975);
FORCEPROP 2 LAST ROOM HEC_VOLT_MONITOR
J 0
(-5600 3900);
DISPLAY 1.021277 (-5600 3900);
PAINT ORANGE (-5600 3900);
DISPLAY INVISIBLE (-5600 3900);
FORCEPROP 1 LAST PATH I79
J 0
(-5620 3915);
DISPLAY 0.872340 (-5620 3915);
PAINT PURPLE (-5620 3915);
DISPLAY INVISIBLE (-5620 3915);
FORCEPROP 2 LAST SEC 1
J 0
(-5600 3975);
DISPLAY 0.936170 (-5600 3975);
PAINT MONO (-5600 3975);
DISPLAY INVISIBLE (-5600 3975);
FORCEADD OFFPAGE..2
(-2525 3025);
FORCEPROP 2 LAST $XR0 119 
J 0
(-2336 3025);
DISPLAY 0.638298 (-2336 3025);
PAINT MONO (-2336 3025);
FORCEPROP 1 LAST COMMENT_BODY TRUE
J 0
(-2570 2930);
DISPLAY 0.872340 (-2570 2930);
PAINT GREEN (-2570 2930);
DISPLAY INVISIBLE (-2570 2930);
FORCEPROP 2 LAST CDS_LIB mstr_standard
J 0
(-2525 3025);
PAINT MONO (-2525 3025);
DISPLAY INVISIBLE (-2525 3025);
FORCEPROP 1 LAST OFFPAGE TRUE
J 0
(-2200 2900);
DISPLAY 0.872340 (-2200 2900);
PAINT GREEN (-2200 2900);
DISPLAY INVISIBLE (-2200 2900);
FORCEPROP 2 LAST PATH I80
J 0
(-2475 3100);
DISPLAY 1.021277 (-2475 3100);
PAINT ORANGE (-2475 3100);
DISPLAY INVISIBLE (-2475 3100);
FORCEADD RES..1
(-3075 3025);
FORCEPROP 1 LASTPIN (-3175 3025) $PN 1
J 0
(-3163 3037);
DISPLAY 0.617021 (-3163 3037);
PAINT ORANGE (-3163 3037);
FORCEPROP 1 LAST WATTAGE 1/16W
J 2
(-3100 2875);
DISPLAY 0.617021 (-3100 2875);
PAINT SKYBLUE (-3100 2875);
FORCEPROP 1 LAST VALUE 33.2
J 2
(-3100 2925);
DISPLAY 0.617021 (-3100 2925);
PAINT SKYBLUE (-3100 2925);
FORCEPROP 1 LAST MATERIAL CHIP
J 0
(-3075 2875);
DISPLAY 0.617021 (-3075 2875);
PAINT SKYBLUE (-3075 2875);
FORCEPROP 1 LAST TOLERANCE 1%
J 0
(-3075 2925);
DISPLAY 0.617021 (-3075 2925);
PAINT SKYBLUE (-3075 2925);
FORCEPROP 1 LAST PART_NUMBER G21796-074
J 0
(-3275 2800);
DISPLAY 0.617021 (-3275 2800);
PAINT BLUE (-3275 2800);
FORCEPROP 1 LAST LOCATION R1U40
J 0
(-3125 3075);
DISPLAY 0.617021 (-3125 3075);
PAINT AQUA (-3125 3075);
FORCEPROP 1 LASTPIN (-2975 3025) $PN 2
J 0
(-3013 3037);
DISPLAY 0.617021 (-3013 3037);
PAINT ORANGE (-3013 3037);
FORCEPROP 1 LAST PACK_TYPE 0402
J 0
(-2825 2875);
DISPLAY 0.617021 (-2825 2875);
PAINT SKYBLUE (-2825 2875);
FORCEPROP 2 LAST CDS_LIB mstr_discrete
J 0
(-3075 3025);
PAINT MONO (-3075 3025);
DISPLAY INVISIBLE (-3075 3025);
FORCEPROP 1 LAST PATH I81
J 0
(-3125 3175);
DISPLAY 0.978723 (-3125 3175);
PAINT WHITE (-3125 3175);
DISPLAY INVISIBLE (-3125 3175);
FORCEPROP 2 LAST CDS_LOCATION R1U40
J 0
(-3125 3075);
DISPLAY 0.617021 (-3125 3075);
PAINT AQUA (-3125 3075);
DISPLAY INVISIBLE (-3125 3075);
FORCEPROP 2 LAST SEC 1
J 0
(-3125 3225);
DISPLAY 0.680851 (-3125 3225);
PAINT MONO (-3125 3225);
DISPLAY INVISIBLE (-3125 3225);
FORCEPROP 2 LAST SEC_TYPE 0402
J 0
(-3125 3225);
DISPLAY 1.021277 (-3125 3225);
PAINT ORANGE (-3125 3225);
DISPLAY INVISIBLE (-3125 3225);
FORCEADD CAD_NOTE..1
(-3275 2700);
FORCEPROP 0 LAST L2 VOLTAGE SENSE TRACES
J 0
(-3425 2525);
DISPLAY 1.021277 (-3425 2525);
PAINT ORANGE (-3425 2525);
FORCEPROP 0 LAST L1 PLACE CLOSE TO THE BMC TO MINIMIZE
J 0
(-3425 2575);
DISPLAY 1.021277 (-3425 2575);
PAINT ORANGE (-3425 2575);
FORCEPROP 1 LAST COMMENT_BODY TRUE
J 0
(-3250 2800);
DISPLAY 0.978723 (-3250 2800);
PAINT ORANGE (-3250 2800);
DISPLAY INVISIBLE (-3250 2800);
FORCEPROP 2 LAST CDS_LIB mstr_symbols
J 0
(-3275 2700);
PAINT ORANGE (-3275 2700);
DISPLAY INVISIBLE (-3275 2700);
FORCEADD DNS..2
(-6270 2845);
PAINT RED (-6270 2845);
FORCEPROP 1 LAST COMMENT_BODY TRUE
R 1
J 0
(-6195 2620);
DISPLAY 0.872340 (-6195 2620);
PAINT GREEN (-6195 2620);
DISPLAY INVISIBLE (-6195 2620);
FORCEPROP 2 LAST CDS_LIB mstr_misc
J 0
(-6270 2845);
PAINT ORANGE (-6270 2845);
DISPLAY INVISIBLE (-6270 2845);
FORCEADD DNS..2
(-6645 2845);
PAINT RED (-6645 2845);
FORCEPROP 1 LAST COMMENT_BODY TRUE
R 1
J 0
(-6570 2620);
DISPLAY 0.872340 (-6570 2620);
PAINT GREEN (-6570 2620);
DISPLAY INVISIBLE (-6570 2620);
FORCEPROP 2 LAST CDS_LIB mstr_misc
J 0
(-6645 2845);
PAINT ORANGE (-6645 2845);
DISPLAY INVISIBLE (-6645 2845);
FORCEADD DESIGN_NOTE..1
(-4500 1600);
FORCEPROP 0 LAST L1 SMBUS ADDRESS: 0X1D
J 0
(-4700 1475);
DISPLAY 1.021277 (-4700 1475);
PAINT ORANGE (-4700 1475);
FORCEPROP 1 LAST COMMENT_BODY TRUE
J 0
(-4475 1700);
DISPLAY 0.978723 (-4475 1700);
PAINT ORANGE (-4475 1700);
DISPLAY INVISIBLE (-4475 1700);
FORCEPROP 2 LAST CDS_LIB mstr_symbols
J 0
(-4500 1600);
PAINT ORANGE (-4500 1600);
DISPLAY INVISIBLE (-4500 1600);
FORCEADD DESIGN_NOTE..1
(-6750 1700);
FORCEPROP 0 LAST L1 BITS [2:1] OF REGISTER 0X0B NEED TO
J 0
(-6950 1575);
DISPLAY 1.021277 (-6950 1575);
PAINT ORANGE (-6950 1575);
FORCEPROP 0 LAST L2 EQUAL 01 TO OPERATE IN MODE 1
J 0
(-6950 1500);
DISPLAY 1.021277 (-6950 1500);
PAINT ORANGE (-6950 1500);
FORCEPROP 1 LAST COMMENT_BODY TRUE
J 0
(-6725 1800);
DISPLAY 0.978723 (-6725 1800);
PAINT ORANGE (-6725 1800);
DISPLAY INVISIBLE (-6725 1800);
FORCEPROP 2 LAST CDS_LIB mstr_symbols
J 0
(-6750 1700);
PAINT ORANGE (-6750 1700);
DISPLAY INVISIBLE (-6750 1700);
FORCEADD INTEL_CORP_BPAGE..1
(-875 -25);
FORCEPROP 1 LAST CDS_CON_LAST_MODIFIED Tue Dec 01 11:52:11 2015
J 0
(-2300 300);
DISPLAY 1.361702 (-2300 300);
PAINT GREEN (-2300 300);
DISPLAY INVISIBLE (-2300 300);
FORCEPROP 1 LAST CUSTOM_TXT_CDS <CURRENT_DESIGN_SHEET> OF <TOTAL_DESIGN_SHEETS>
J 0
(-1375 0);
PAINT GREEN (-1375 0);
FORCEPROP 1 LAST CUSTOM_TXT_CDS <CON_LAST_MODIFIED>
J 0
(-2800 325);
PAINT GREEN (-2800 325);
FORCEPROP 2 LAST CUSTOM_TXT_CDS <XR_PAGE_TITLE>
J 0
(-8765 5225);
DISPLAY 0.638298 (-8765 5225);
PAINT PINK (-8765 5225);
DISPLAY INVISIBLE (-8765 5225);
FORCEPROP 1 LAST SCH_ADDRESS3 Santa Clara, CA 95052-8119
J 0
(-4850 0);
DISPLAY 0.617021 (-4850 0);
PAINT GREEN (-4850 0);
FORCEPROP 1 LAST SCH_TITLE VOLTAGE MONITORING IC
J 0
(-8825 25);
DISPLAY 1.212766 (-8825 25);
PAINT ORANGE (-8825 25);
FORCEPROP 1 LAST SCH_ADDRESS2 P.O. BOX 58119
J 0
(-4850 50);
DISPLAY 0.617021 (-4850 50);
PAINT GREEN (-4850 50);
FORCEPROP 1 LAST SCH_ADDRESS1 2200 Mission College Blvd.
J 0
(-4850 100);
DISPLAY 0.617021 (-4850 100);
PAINT GREEN (-4850 100);
FORCEPROP 1 LAST SCH_NUMBER H4694802
J 0
(-2175 125);
DISPLAY 1.212766 (-2175 125);
PAINT YELLOW (-2175 125);
FORCEPROP 1 LAST SCH_DEPT BESD
J 1
(-5325 75);
DISPLAY 1.212766 (-5325 75);
PAINT YELLOW (-5325 75);
FORCEPROP 1 LAST SCH_REV 2.420
J 0
(-1125 125);
DISPLAY 0.978723 (-1125 125);
PAINT YELLOW (-1125 125);
FORCEPROP 1 LAST COMMENT_BODY TRUE
J 0
(-863 -13);
DISPLAY 0.617021 (-863 -13);
PAINT GREEN (-863 -13);
DISPLAY INVISIBLE (-863 -13);
FORCEPROP 2 LAST CDS_LIB mstr_symbols
J 0
(-875 -25);
DISPLAY 1.361702 (-875 -25);
PAINT ORANGE (-875 -25);
DISPLAY INVISIBLE (-875 -25);
FORCEPROP 2 LAST PAGE_BORDER TRUE
J 0
(-8765 5225);
DISPLAY 0.851064 (-8765 5225);
PAINT PINK (-8765 5225);
DISPLAY INVISIBLE (-8765 5225);
FORCEPROP 2 LAST CDS_XR_PAGE_TITLE CR-165 : @BASEBOARD_FAB2_LIB.BASEBOARD_FAB2(SCH_1):PAGE165
J 0
(-8765 5225);
DISPLAY 0.638298 (-8765 5225);
PAINT PINK (-8765 5225);
DISPLAY INVISIBLE (-8765 5225);
WIRE 16 -1 (-6275 2150)(-6275 2250);
WIRE 16 -1 (-6650 2150)(-6650 2250);
WIRE 16 -1 (-5050 3300)(-5050 3425);
WIRE 16 -1 (-5750 3750)(-5625 3750);
WIRE 16 -1 (-5750 3900)(-5750 3750);
WIRE 16 -1 (-6275 2950)(-6275 3050);
WIRE 16 -1 (-6650 2950)(-6650 3050);
WIRE 16 -1 (-3925 2175)(-3975 2175);
WIRE 16 -1 (-3925 1950)(-3925 2175);
WIRE 16 -1 (-5325 3300)(-5325 3425);
WIRE 16 -1 (-3650 3475)(-3650 3675);
WIRE 16 -1 (-2975 3025)(-2575 3025);
FORCEPROP 2 LAST SIG_NAME IRQ_VM_INT_N
J 0
(-2935 3035);
DISPLAY 0.617021 (-2935 3035);
PAINT ORANGE (-2935 3035);
WIRE 16 -1 (-3650 3275)(-3650 3025);
FORCEPROP 2 LAST SIG_NAME IRQ_VM_INT_R_N
J 0
(-3510 3035);
DISPLAY 0.617021 (-3510 3035);
PAINT ORANGE (-3510 3035);
FORCEPROP 2 LASTPROP $XRERR UNIQUE?
J 0
(-3750 3035);
DISPLAY 0.638298 (-3750 3035);
PAINT MONO (-3750 3035);
DISPLAY INVISIBLE (-3750 3035);
WIRE 16 -1 (-3650 3025)(-3175 3025);
WIRE 16 -1 (-3650 3025)(-3975 3025);
WIRE 16 -1 (-5050 3750)(-4825 3750);
WIRE 16 -1 (-5050 3625)(-5050 3750);
WIRE 16 -1 (-5325 3750)(-5050 3750);
FORCEPROP 0 LAST VOLTAGE +3.3V
J 0
(-5275 3825);
DISPLAY 1.021277 (-5275 3825);
PAINT SKYBLUE (-5275 3825);
DISPLAY INVISIBLE (-5275 3825);
FORCEPROP 2 LAST SIG_NAME P3V3_FB_ADC128_VCC
J 0
(-5285 3760);
DISPLAY 0.617021 (-5285 3760);
PAINT ORANGE (-5285 3760);
FORCEPROP 2 LASTPROP $XRERR UNIQUE?
J 0
(-5525 3760);
DISPLAY 0.638298 (-5525 3760);
PAINT MONO (-5525 3760);
DISPLAY INVISIBLE (-5525 3760);
WIRE 16 -1 (-4825 3750)(-4825 3025);
WIRE 16 -1 (-4825 3025)(-4675 3025);
WIRE 16 -1 (-5325 3625)(-5325 3750);
WIRE 16 -1 (-5425 3750)(-5325 3750);
WIRE 16 -1 (-5600 2775)(-4675 2775);
FORCEPROP 2 LAST SIG_NAME TP_ADC128_VREF
J 0
(-5535 2785);
DISPLAY 0.617021 (-5535 2785);
PAINT ORANGE (-5535 2785);
FORCEPROP 2 LASTPROP $XRERR UNIQUE?
J 0
(-5840 2775);
DISPLAY 0.638298 (-5840 2775);
PAINT MONO (-5840 2775);
DISPLAY INVISIBLE (-5840 2775);
WIRE 16 -1 (-5600 2925)(-4675 2925);
FORCEPROP 2 LAST SIG_NAME SMB_SENSOR_PCH_STBY_LVC3_SCL
J 0
(-5535 2935);
DISPLAY 0.617021 (-5535 2935);
PAINT ORANGE (-5535 2935);
WIRE 16 -1 (-5600 2875)(-4675 2875);
FORCEPROP 2 LAST SIG_NAME SMB_SENSOR_PCH_STBY_LVC3_SDA
J 0
(-5535 2885);
DISPLAY 0.617021 (-5535 2885);
PAINT ORANGE (-5535 2885);
WIRE 16 -1 (-5600 2525)(-4675 2525);
FORCEPROP 2 LAST SIG_NAME A_P3V_BAT_SCALED
J 0
(-5560 2535);
DISPLAY 0.617021 (-5560 2535);
PAINT ORANGE (-5560 2535);
WIRE 16 -1 (-5600 2475)(-4675 2475);
FORCEPROP 2 LAST SIG_NAME A_P5V_STBY_SCALED
J 0
(-5560 2485);
DISPLAY 0.617021 (-5560 2485);
PAINT ORANGE (-5560 2485);
WIRE 16 -1 (-5600 2425)(-4675 2425);
FORCEPROP 2 LAST SIG_NAME A_P3V3_STBY_SCALED
J 0
(-5560 2435);
DISPLAY 0.617021 (-5560 2435);
PAINT ORANGE (-5560 2435);
WIRE 16 -1 (-5600 2375)(-4675 2375);
FORCEPROP 2 LAST SIG_NAME A_PVNN_STBY_PCH_SENSOR
J 0
(-5560 2385);
DISPLAY 0.617021 (-5560 2385);
PAINT ORANGE (-5560 2385);
WIRE 16 -1 (-5600 2325)(-4675 2325);
FORCEPROP 2 LAST SIG_NAME A_P1V05_STBY_PCH_SENSOR
J 0
(-5560 2335);
DISPLAY 0.617021 (-5560 2335);
PAINT ORANGE (-5560 2335);
WIRE 16 -1 (-5600 2275)(-4675 2275);
FORCEPROP 2 LAST SIG_NAME A_P12V_STBY_SCALED
J 0
(-5560 2285);
DISPLAY 0.617021 (-5560 2285);
PAINT ORANGE (-5560 2285);
WIRE 16 -1 (-5600 2225)(-4675 2225);
FORCEPROP 2 LAST SIG_NAME A_P5V_SCALED
J 0
(-5560 2235);
DISPLAY 0.617021 (-5560 2235);
PAINT ORANGE (-5560 2235);
WIRE 16 -1 (-5600 2175)(-4675 2175);
FORCEPROP 2 LAST SIG_NAME A_P3V3_SCALED
J 0
(-5560 2185);
DISPLAY 0.617021 (-5560 2185);
PAINT ORANGE (-5560 2185);
WIRE 16 -1 (-6650 2675)(-4675 2675);
FORCEPROP 2 LAST SIG_NAME FM_ADC128_A1
J 0
(-5985 2685);
DISPLAY 0.617021 (-5985 2685);
PAINT ORANGE (-5985 2685);
FORCEPROP 2 LASTPROP $XRERR UNIQUE?
J 0
(-6225 2685);
DISPLAY 0.638298 (-6225 2685);
PAINT MONO (-6225 2685);
DISPLAY INVISIBLE (-6225 2685);
WIRE 16 -1 (-6650 2675)(-6650 2750);
WIRE 16 -1 (-6650 2450)(-6650 2675);
WIRE 16 -1 (-6275 2625)(-4675 2625);
FORCEPROP 2 LAST SIG_NAME FM_ADC128_A0
J 0
(-5935 2635);
DISPLAY 0.617021 (-5935 2635);
PAINT ORANGE (-5935 2635);
FORCEPROP 2 LASTPROP $XRERR UNIQUE?
J 0
(-6175 2635);
DISPLAY 0.638298 (-6175 2635);
PAINT MONO (-6175 2635);
DISPLAY INVISIBLE (-6175 2635);
WIRE 16 -1 (-6275 2625)(-6275 2750);
WIRE 16 -1 (-6275 2450)(-6275 2625);
DOT 1 (-6650 2675);
DOT 1 (-6275 2625);
DOT 1 (-5325 3750);
DOT 1 (-5050 3750);
DOT 1 (-3650 3025);
FORCENOTE
ROOM=HEC_VOLT_MONITOR
(-8825 225) 0;
DISPLAY LEFT (-8825 225);
DISPLAY 1.361702 (-8825 225);
PAINT PURPLE (-8825 225);
FORCENOTE
BOM_COST=SM_HM
(-8825 125) 0;
DISPLAY LEFT (-8825 125);
DISPLAY 1.361702 (-8825 125);
PAINT PURPLE (-8825 125);
QUIT
